# S9S_MB_2U (Grand Teton) — schematic netlist excerpt (pin names and nets, part order shuffled) for the footprints in the layout excerpt that follows; sources: Cadence DE-HDL packaged netlist, KiCad conversion of 03242023_DA0F0TMBIJ0_F0T_Motherboard_J_brd_V01_OCP.brd

R3243  Q_RES  2.2K 5% EMPTY  pkg 0402LF  page 241 : A = SMB_OCP_V3_2_3V3AUX_SDA ; B = P3V3_AUX
PC2000  Q_CAP  0.022UF 16V 10% X7R  pkg 0402  page 262 : A = P1V05_PCH_AUX_REF ; B = GND
C879  Q_CAP_DIFFBUS  DIFF BUS_0.22UF 6.3V 20% X6S  pkg C0201  page 174 : \1\ = P5E_CPU0_PE3_TX_C_DP<11> ; \2\ = P5E_CPU0_PE3_TX_DP<11>

(kicad_pcb
	(version 20260206)
	(generator "pcbnew")
	(generator_version "10.0")
	(general
		(thickness 1.6)
		(legacy_teardrops no)
	)
	(paper "A4")
	(title_block
		(title "03242023_DA0F0TMBIJ0_F0T_Motherboard_J_brd_V01_OCP.brd")
		(comment 1 "Grand Teton / footprints 639-641 of 6105")
	)
	(layers
		(0 "F.Cu" signal "TOP")
		(4 "In1.Cu" signal "GND")
		(6 "In2.Cu" signal "IN1")
		(8 "In3.Cu" signal "GND1")
		(10 "In4.Cu" signal "IN2")
		(12 "In5.Cu" signal "GND2")
		(14 "In6.Cu" signal "IN3")
		(16 "In7.Cu" signal "GND3")
		(18 "In8.Cu" signal "VCC")
		(20 "In9.Cu" signal "VCC1")
		(22 "In10.Cu" signal "GND4")
		(24 "In11.Cu" signal "IN4")
		(26 "In12.Cu" signal "GND5")
		(28 "In13.Cu" signal "IN5")
		(30 "In14.Cu" signal "GND6")
		(32 "In15.Cu" signal "IN6")
		(34 "In16.Cu" signal "GND7")
		(2 "B.Cu" signal "BOTTOM")
		(9 "F.Adhes" user "F.Adhesive")
		(11 "B.Adhes" user "B.Adhesive")
		(13 "F.Paste" user "Package Geometry/Pastemask Top")
		(15 "B.Paste" user "Package Geometry/Pastemask Bottom")
		(5 "F.SilkS" user "Ref Des/Silkscreen Top")
		(7 "B.SilkS" user "Ref Des/Silkscreen Bottom")
		(1 "F.Mask" user "Board Geometry/Soldermask Top")
		(3 "B.Mask" user "Board Geometry/Soldermask Bottom")
		(17 "Dwgs.User" user "User.Drawings")
		(19 "Cmts.User" user "User.Comments")
		(21 "Eco1.User" user "User.Eco1")
		(23 "Eco2.User" user "User.Eco2")
		(25 "Edge.Cuts" user "Board Geometry/Outline")
		(27 "Margin" user)
		(31 "F.CrtYd" user "Package Geometry/Place Bound Top")
		(29 "B.CrtYd" user "Package Geometry/Place Bound Bottom")
		(35 "F.Fab" user "Ref Des/Assembly Top")
		(33 "B.Fab" user "Ref Des/Assembly Bottom")
	)
	(footprint ""
		(layer "F.Cu")
		(at 109.337856 -32.64281)
		(property "Reference" "R3243"
			(at 0 0 0)
			(layer "F.SilkS")
			(hide yes)
			(effects
				(font
					(size 1.27 1.27)
				)
			)
		)
		(property "Value" ""
			(at 0 0 0)
			(layer "F.Fab")
			(effects
				(font
					(size 1.27 1.27)
				)
			)
		)
		(duplicate_pad_numbers_are_jumpers no)
		(fp_line
			(start -0.7874 -0.4064)
			(end 0.7874 -0.4064)
			(stroke
				(width 0.1524)
				(type default)
			)
			(layer "F.SilkS")
		)
		(fp_line
			(start -0.7874 0.4064)
			(end -0.7874 -0.4064)
			(stroke
				(width 0.1524)
				(type default)
			)
			(layer "F.SilkS")
		)
		(fp_line
			(start 0.7874 -0.4064)
			(end 0.7874 0.4064)
			(stroke
				(width 0.1524)
				(type default)
			)
			(layer "F.SilkS")
		)
		(fp_line
			(start 0.7874 0.4064)
			(end -0.7874 0.4064)
			(stroke
				(width 0.1524)
				(type default)
			)
			(layer "F.SilkS")
		)
		(fp_line
			(start -0.67945 -0.305054)
			(end -0.12065 -0.305054)
			(stroke
				(width 0.1)
				(type default)
			)
			(layer "F.Fab")
		)
		(fp_line
			(start -0.67945 0.3048)
			(end -0.67945 -0.305054)
			(stroke
				(width 0.1)
				(type default)
			)
			(layer "F.Fab")
		)
		(fp_line
			(start -0.12065 -0.305054)
			(end -0.12065 -0.2794)
			(stroke
				(width 0.1)
				(type default)
			)
			(layer "F.Fab")
		)
		(fp_line
			(start -0.12065 -0.2794)
			(end 0.12065 -0.2794)
			(stroke
				(width 0.1)
				(type default)
			)
			(layer "F.Fab")
		)
		(fp_line
			(start -0.12065 0.2794)
			(end -0.12065 0.3048)
			(stroke
				(width 0.1)
				(type default)
			)
			(layer "F.Fab")
		)
		(fp_line
			(start -0.12065 0.3048)
			(end -0.67945 0.3048)
			(stroke
				(width 0.1)
				(type default)
			)
			(layer "F.Fab")
		)
		(fp_line
			(start 0.120396 0.2794)
			(end -0.12065 0.2794)
			(stroke
				(width 0.1)
				(type default)
			)
			(layer "F.Fab")
		)
		(fp_line
			(start 0.120396 0.3048)
			(end 0.120396 0.2794)
			(stroke
				(width 0.1)
				(type default)
			)
			(layer "F.Fab")
		)
		(fp_line
			(start 0.12065 -0.3048)
			(end 0.67945 -0.3048)
			(stroke
				(width 0.1)
				(type default)
			)
			(layer "F.Fab")
		)
		(fp_line
			(start 0.12065 -0.2794)
			(end 0.12065 -0.3048)
			(stroke
				(width 0.1)
				(type default)
			)
			(layer "F.Fab")
		)
		(fp_line
			(start 0.67945 -0.3048)
			(end 0.67945 0.3048)
			(stroke
				(width 0.1)
				(type default)
			)
			(layer "F.Fab")
		)
		(fp_line
			(start 0.67945 0.3048)
			(end 0.120396 0.3048)
			(stroke
				(width 0.1)
				(type default)
			)
			(layer "F.Fab")
		)
		(pad "1" smd circle
			(at -0.40005 0)
			(size 0 0)
			(layers "F.Cu" "F.Mask" "F.Paste")
			(net "SMB_OCP_V3_2_3V3AUX_SDA")
		)
		(pad "2" smd circle
			(at 0.40005 0)
			(size 0 0)
			(layers "F.Cu" "F.Mask" "F.Paste")
			(net "P3V3_AUX")
		)
	)
	(footprint ""
		(layer "F.Cu")
		(at 385.91109 -408.517344 -90)
		(property "Reference" "C879"
			(at 0 0 270)
			(layer "F.SilkS")
			(hide yes)
			(effects
				(font
					(size 1.27 1.27)
				)
			)
		)
		(property "Value" ""
			(at 0 0 270)
			(layer "F.Fab")
			(effects
				(font
					(size 1.27 1.27)
				)
			)
		)
		(duplicate_pad_numbers_are_jumpers no)
		(fp_line
			(start -0.299974 0.150114)
			(end -0.299974 -0.150114)
			(stroke
				(width 0.1)
				(type default)
			)
			(layer "F.Fab")
		)
		(fp_line
			(start 0.299974 0.150114)
			(end -0.299974 0.150114)
			(stroke
				(width 0.1)
				(type default)
			)
			(layer "F.Fab")
		)
		(fp_line
			(start -0.299974 -0.150114)
			(end 0.299974 -0.150114)
			(stroke
				(width 0.1)
				(type default)
			)
			(layer "F.Fab")
		)
		(fp_line
			(start 0.299974 -0.150114)
			(end 0.299974 0.150114)
			(stroke
				(width 0.1)
				(type default)
			)
			(layer "F.Fab")
		)
		(pad "1" smd rect
			(at -0.2667 0 270)
			(size 0.3048 0.381)
			(layers "F.Cu" "F.Mask" "F.Paste")
			(net "P5E_CPU0_PE3_TX_C_DP<11>")
		)
		(pad "2" smd rect
			(at 0.2667 0 270)
			(size 0.3048 0.381)
			(layers "F.Cu" "F.Mask" "F.Paste")
			(net "P5E_CPU0_PE3_TX_DP<11>")
		)
	)
	(footprint ""
		(layer "F.Cu")
		(at 262.84809 -75.61834 90)
		(property "Reference" "PC2000"
			(at 0 0 90)
			(layer "F.SilkS")
			(hide yes)
			(effects
				(font
					(size 1.27 1.27)
				)
			)
		)
		(property "Value" ""
			(at 0 0 90)
			(layer "F.Fab")
			(effects
				(font
					(size 1.27 1.27)
				)
			)
		)
		(duplicate_pad_numbers_are_jumpers no)
		(fp_line
			(start 0.7874 -0.4064)
			(end 0.7874 0.4064)
			(stroke
				(width 0.1524)
				(type default)
			)
			(layer "F.SilkS")
		)
		(fp_line
			(start -0.7874 -0.4064)
			(end 0.7874 -0.4064)
			(stroke
				(width 0.1524)
				(type default)
			)
			(layer "F.SilkS")
		)
		(fp_line
			(start 0.7874 0.4064)
			(end -0.7874 0.4064)
			(stroke
				(width 0.1524)
				(type default)
			)
			(layer "F.SilkS")
		)
		(fp_line
			(start -0.7874 0.4064)
			(end -0.7874 -0.4064)
			(stroke
				(width 0.1524)
				(type default)
			)
			(layer "F.SilkS")
		)
		(fp_line
			(start -0.12065 -0.305054)
			(end -0.12065 -0.2794)
			(stroke
				(width 0.1)
				(type default)
			)
			(layer "F.Fab")
		)
		(fp_line
			(start -0.67945 -0.305054)
			(end -0.12065 -0.305054)
			(stroke
				(width 0.1)
				(type default)
			)
			(layer "F.Fab")
		)
		(fp_line
			(start 0.67945 -0.3048)
			(end 0.67945 0.3048)
			(stroke
				(width 0.1)
				(type default)
			)
			(layer "F.Fab")
		)
		(fp_line
			(start 0.12065 -0.3048)
			(end 0.67945 -0.3048)
			(stroke
				(width 0.1)
				(type default)
			)
			(layer "F.Fab")
		)
		(fp_line
			(start 0.12065 -0.2794)
			(end 0.12065 -0.3048)
			(stroke
				(width 0.1)
				(type default)
			)
			(layer "F.Fab")
		)
		(fp_line
			(start -0.12065 -0.2794)
			(end 0.12065 -0.2794)
			(stroke
				(width 0.1)
				(type default)
			)
			(layer "F.Fab")
		)
		(fp_line
			(start 0.120396 0.2794)
			(end -0.12065 0.2794)
			(stroke
				(width 0.1)
				(type default)
			)
			(layer "F.Fab")
		)
		(fp_line
			(start -0.12065 0.2794)
			(end -0.12065 0.3048)
			(stroke
				(width 0.1)
				(type default)
			)
			(layer "F.Fab")
		)
		(fp_line
			(start 0.67945 0.3048)
			(end 0.120396 0.3048)
			(stroke
				(width 0.1)
				(type default)
			)
			(layer "F.Fab")
		)
		(fp_line
			(start 0.120396 0.3048)
			(end 0.120396 0.2794)
			(stroke
				(width 0.1)
				(type default)
			)
			(layer "F.Fab")
		)
		(fp_line
			(start -0.12065 0.3048)
			(end -0.67945 0.3048)
			(stroke
				(width 0.1)
				(type default)
			)
			(layer "F.Fab")
		)
		(fp_line
			(start -0.67945 0.3048)
			(end -0.67945 -0.305054)
			(stroke
				(width 0.1)
				(type default)
			)
			(layer "F.Fab")
		)
		(pad "1" smd circle
			(at -0.40005 0 90)
			(size 0 0)
			(layers "F.Cu" "F.Mask" "F.Paste")
			(net "P1V05_PCH_AUX_REF")
		)
		(pad "2" smd circle
			(at 0.40005 0 90)
			(size 0 0)
			(layers "F.Cu" "F.Mask" "F.Paste")
			(net "GND")
		)
	)
)
